# T6G (Grand Teton) — schematic netlist excerpt (pin names and nets, part order shuffled) for the footprints in the layout excerpt that follows; sources: Cadence DE-HDL packaged netlist, KiCad conversion of 04192023_DAF0TMB3IC0_F0TG_MB_C_brd_V02_OCP.brd

R3393  Q_RES  0 5% CHIP  pkg 0402LF  page 250 : A = SMB_IOEXP_3V3AUX_SCL_R ; B = SMB_IOEXP_3V3AUX_SCL

PL51  Q_INDUCTOR4P_14  150NH IND  pkg L_TLM117513Q-151QL_11X7-5XA  page 194
  \1\  = SW_PVDDCR_CPU0_P0_SW1
  \2\  = IND_CPU0_P0_CPL5
  \3\  = IND_CPU0_P0_CPL1
  \4\  = PVDDCR_CPU0_P0

(kicad_pcb
	(version 20260206)
	(generator "pcbnew")
	(generator_version "10.0")
	(general
		(thickness 1.6)
		(legacy_teardrops no)
	)
	(paper "A4")
	(title_block
		(title "04192023_DAF0TMB3IC0_F0TG_MB_C_brd_V02_OCP.brd")
		(comment 1 "Grand Teton / footprints 1726-1727 of 8354")
	)
	(layers
		(0 "F.Cu" signal "TOP")
		(4 "In1.Cu" signal "GND")
		(6 "In2.Cu" signal "IN1")
		(8 "In3.Cu" signal "GND1")
		(10 "In4.Cu" signal "IN2")
		(12 "In5.Cu" signal "GND2")
		(14 "In6.Cu" signal "IN3")
		(16 "In7.Cu" signal "GND3")
		(18 "In8.Cu" signal "VCC")
		(20 "In9.Cu" signal "VCC1")
		(22 "In10.Cu" signal "GND4")
		(24 "In11.Cu" signal "IN4")
		(26 "In12.Cu" signal "GND5")
		(28 "In13.Cu" signal "IN5")
		(30 "In14.Cu" signal "GND6")
		(32 "In15.Cu" signal "IN6")
		(34 "In16.Cu" signal "GND7")
		(2 "B.Cu" signal "BOTTOM")
		(9 "F.Adhes" user "F.Adhesive")
		(11 "B.Adhes" user "B.Adhesive")
		(13 "F.Paste" user "Package Geometry/Pastemask Top")
		(15 "B.Paste" user "Package Geometry/Pastemask Bottom")
		(5 "F.SilkS" user "Ref Des/Silkscreen Top")
		(7 "B.SilkS" user "Ref Des/Silkscreen Bottom")
		(1 "F.Mask" user "Board Geometry/Soldermask Top")
		(3 "B.Mask" user "Board Geometry/Soldermask Bottom")
		(17 "Dwgs.User" user "User.Drawings")
		(19 "Cmts.User" user "User.Comments")
		(21 "Eco1.User" user "User.Eco1")
		(23 "Eco2.User" user "User.Eco2")
		(25 "Edge.Cuts" user "Board Geometry/Outline")
		(27 "Margin" user)
		(31 "F.CrtYd" user "Package Geometry/Place Bound Top")
		(29 "B.CrtYd" user "Package Geometry/Place Bound Bottom")
		(35 "F.Fab" user "Ref Des/Assembly Top")
		(33 "B.Fab" user "Ref Des/Assembly Bottom")
	)
	(footprint ""
		(layer "F.Cu")
		(at 279.513792 -117.69217 180)
		(property "Reference" "R3393"
			(at 0 0 180)
			(layer "F.SilkS")
			(hide yes)
			(effects
				(font
					(size 1.27 1.27)
				)
			)
		)
		(property "Value" ""
			(at 0 0 180)
			(layer "F.Fab")
			(effects
				(font
					(size 1.27 1.27)
				)
			)
		)
		(duplicate_pad_numbers_are_jumpers no)
		(fp_line
			(start 0.7874 0.4064)
			(end -0.7874 0.4064)
			(stroke
				(width 0.1524)
				(type default)
			)
			(layer "F.SilkS")
		)
		(fp_line
			(start 0.7874 -0.4064)
			(end 0.7874 0.4064)
			(stroke
				(width 0.1524)
				(type default)
			)
			(layer "F.SilkS")
		)
		(fp_line
			(start -0.7874 0.4064)
			(end -0.7874 -0.4064)
			(stroke
				(width 0.1524)
				(type default)
			)
			(layer "F.SilkS")
		)
		(fp_line
			(start -0.7874 -0.4064)
			(end 0.7874 -0.4064)
			(stroke
				(width 0.1524)
				(type default)
			)
			(layer "F.SilkS")
		)
		(fp_line
			(start 0.67945 0.3048)
			(end 0.120396 0.3048)
			(stroke
				(width 0.1)
				(type default)
			)
			(layer "F.Fab")
		)
		(fp_line
			(start 0.67945 -0.3048)
			(end 0.67945 0.3048)
			(stroke
				(width 0.1)
				(type default)
			)
			(layer "F.Fab")
		)
		(fp_line
			(start 0.12065 -0.2794)
			(end 0.12065 -0.3048)
			(stroke
				(width 0.1)
				(type default)
			)
			(layer "F.Fab")
		)
		(fp_line
			(start 0.12065 -0.3048)
			(end 0.67945 -0.3048)
			(stroke
				(width 0.1)
				(type default)
			)
			(layer "F.Fab")
		)
		(fp_line
			(start 0.120396 0.3048)
			(end 0.120396 0.2794)
			(stroke
				(width 0.1)
				(type default)
			)
			(layer "F.Fab")
		)
		(fp_line
			(start 0.120396 0.2794)
			(end -0.12065 0.2794)
			(stroke
				(width 0.1)
				(type default)
			)
			(layer "F.Fab")
		)
		(fp_line
			(start -0.12065 0.3048)
			(end -0.67945 0.3048)
			(stroke
				(width 0.1)
				(type default)
			)
			(layer "F.Fab")
		)
		(fp_line
			(start -0.12065 0.2794)
			(end -0.12065 0.3048)
			(stroke
				(width 0.1)
				(type default)
			)
			(layer "F.Fab")
		)
		(fp_line
			(start -0.12065 -0.2794)
			(end 0.12065 -0.2794)
			(stroke
				(width 0.1)
				(type default)
			)
			(layer "F.Fab")
		)
		(fp_line
			(start -0.12065 -0.305054)
			(end -0.12065 -0.2794)
			(stroke
				(width 0.1)
				(type default)
			)
			(layer "F.Fab")
		)
		(fp_line
			(start -0.67945 0.3048)
			(end -0.67945 -0.305054)
			(stroke
				(width 0.1)
				(type default)
			)
			(layer "F.Fab")
		)
		(fp_line
			(start -0.67945 -0.305054)
			(end -0.12065 -0.305054)
			(stroke
				(width 0.1)
				(type default)
			)
			(layer "F.Fab")
		)
		(pad "1" smd circle
			(at -0.40005 0 180)
			(size 0 0)
			(layers "F.Cu" "F.Mask" "F.Paste")
			(net "SMB_IOEXP_3V3AUX_SCL_R")
		)
		(pad "2" smd circle
			(at 0.40005 0 180)
			(size 0 0)
			(layers "F.Cu" "F.Mask" "F.Paste")
			(net "SMB_IOEXP_3V3AUX_SCL")
		)
	)
	(footprint ""
		(layer "F.Cu")
		(at 364.196122 -187.088526 180)
		(property "Reference" "PL51"
			(at 3.7465 7.340854 0)
			(unlocked yes)
			(layer "F.SilkS")
			(effects
				(font
					(size 0.7874 0.5842)
					(thickness 0.1524)
				)
				(justify left)
			)
		)
		(property "Value" ""
			(at 0 0 180)
			(layer "F.Fab")
			(effects
				(font
					(size 1.27 1.27)
				)
			)
		)
		(duplicate_pad_numbers_are_jumpers no)
		(fp_line
			(start 3.750056 5.500116)
			(end 3.750056 -5.500116)
			(stroke
				(width 0.1524)
				(type default)
			)
			(layer "F.SilkS")
		)
		(fp_line
			(start 3.750056 -5.500116)
			(end 2.393442 -5.500116)
			(stroke
				(width 0.1524)
				(type default)
			)
			(layer "F.SilkS")
		)
		(fp_line
			(start 2.393442 5.500116)
			(end 3.750056 5.500116)
			(stroke
				(width 0.1524)
				(type default)
			)
			(layer "F.SilkS")
		)
		(fp_line
			(start -2.393442 5.500116)
			(end -3.750056 5.500116)
			(stroke
				(width 0.1524)
				(type default)
			)
			(layer "F.SilkS")
		)
		(fp_line
			(start -3.750056 5.500116)
			(end -3.750056 -5.500116)
			(stroke
				(width 0.1524)
				(type default)
			)
			(layer "F.SilkS")
		)
		(fp_line
			(start -3.750056 -5.500116)
			(end -2.393442 -5.500116)
			(stroke
				(width 0.1524)
				(type default)
			)
			(layer "F.SilkS")
		)
		(fp_poly
			(pts
				(xy -4.035806 -3.262122) (xy -4.395216 -2.1844) (xy -5.113528 -2.902712)
			)
			(stroke
				(width 0)
				(type default)
			)
			(fill yes)
			(layer "F.SilkS")
		)
		(fp_line
			(start 3.750056 5.500116)
			(end 3.750056 -5.500116)
			(stroke
				(width 0.1)
				(type default)
			)
			(layer "F.Fab")
		)
		(fp_line
			(start 3.750056 -5.500116)
			(end -3.750056 -5.500116)
			(stroke
				(width 0.1)
				(type default)
			)
			(layer "F.Fab")
		)
		(fp_line
			(start -3.750056 5.500116)
			(end 3.750056 5.500116)
			(stroke
				(width 0.1)
				(type default)
			)
			(layer "F.Fab")
		)
		(fp_line
			(start -3.750056 -5.500116)
			(end -3.750056 5.500116)
			(stroke
				(width 0.1)
				(type default)
			)
			(layer "F.Fab")
		)
		(fp_poly
			(pts
				(xy -4.9276 -4.757928) (xy -4.9276 -3.741928) (xy -3.9116 -4.249928)
			)
			(stroke
				(width 0)
				(type default)
			)
			(fill yes)
			(layer "F.Fab")
		)
		(pad "1" smd rect
			(at 0 -4.249928 90)
			(size 2.413 4.5212)
			(layers "F.Cu" "F.Mask" "F.Paste")
			(net "SW_PVDDCR_CPU0_P0_SW1")
		)
		(pad "2" smd rect
			(at 0 -1.175004 90)
			(size 1.3716 4.5212)
			(layers "F.Cu" "F.Mask" "F.Paste")
			(net "IND_CPU0_P0_CPL5")
		)
		(pad "3" smd rect
			(at 0 1.175004 90)
			(size 1.3716 4.5212)
			(layers "F.Cu" "F.Mask" "F.Paste")
			(net "IND_CPU0_P0_CPL1")
		)
		(pad "4" smd rect
			(at 0 4.249928 90)
			(size 2.413 4.5212)
			(layers "F.Cu" "F.Mask" "F.Paste")
			(net "PVDDCR_CPU0_P0")
		)
	)
)
